# BASEBOARD_FAB2 (Tioga Pass) — schematic netlist excerpt (pin names and nets, part order shuffled) for the footprints in the layout excerpt that follows; sources: Cadence DE-HDL packaged netlist, KiCad conversion of Wiwynn_Tioga_Pass_MB.brd

C5G91  CAP_A  22.0UF 4V 20% X6S  pkg 0603V  page 243 : A = PVDDQ_GHJ ; B = GND
C3L23  CAP_A  22.0UF 4V 20% X6S  pkg 0603V  page 132 : A = PVNN_PCH_STBY ; B = GND
R6P46  RES  100.0 1% CHIP  pkg 0402  page 112 : A = PVCCIO_CPU0 ; B = XDP_CPU_MBP1_N

(kicad_pcb
	(version 20260206)
	(generator "pcbnew")
	(generator_version "10.0")
	(general
		(thickness 1.6)
		(legacy_teardrops no)
	)
	(paper "A4")
	(title_block
		(title "Wiwynn_Tioga_Pass_MB.brd")
		(comment 1 "Tioga Pass / footprints 3789-3791 of 4770")
	)
	(layers
		(0 "F.Cu" signal "TOP")
		(4 "In1.Cu" signal "L2GND")
		(6 "In2.Cu" signal "L3")
		(8 "In3.Cu" signal "L4GND")
		(10 "In4.Cu" signal "L5")
		(12 "In5.Cu" signal "L6GND")
		(14 "In6.Cu" signal "L7VCC")
		(16 "In7.Cu" signal "L8VCC")
		(18 "In8.Cu" signal "L9GND")
		(20 "In9.Cu" signal "L10")
		(22 "In10.Cu" signal "L11GND")
		(24 "In11.Cu" signal "L12")
		(26 "In12.Cu" signal "L13GND")
		(2 "B.Cu" signal "BOTTOM")
		(9 "F.Adhes" user "F.Adhesive")
		(11 "B.Adhes" user "B.Adhesive")
		(13 "F.Paste" user "Package Geometry/Pastemask Top")
		(15 "B.Paste" user "Package Geometry/Pastemask Bottom")
		(5 "F.SilkS" user "Ref Des/Silkscreen Top")
		(7 "B.SilkS" user "Ref Des/Silkscreen Bottom")
		(1 "F.Mask" user "Board Geometry/Soldermask Top")
		(3 "B.Mask" user "Board Geometry/Soldermask Bottom")
		(17 "Dwgs.User" user "User.Drawings")
		(19 "Cmts.User" user "User.Comments")
		(21 "Eco1.User" user "User.Eco1")
		(23 "Eco2.User" user "User.Eco2")
		(25 "Edge.Cuts" user "Board Geometry/Outline")
		(27 "Margin" user)
		(31 "F.CrtYd" user "Package Geometry/Place Bound Top")
		(29 "B.CrtYd" user "Package Geometry/Place Bound Bottom")
		(35 "F.Fab" user "Ref Des/Assembly Top")
		(33 "B.Fab" user "Ref Des/Assembly Bottom")
	)
	(footprint ""
		(layer "B.Cu")
		(at 374.015 -138.1125)
		(property "Reference" "C3L23"
			(at 0 0 0)
			(layer "B.SilkS")
			(hide yes)
			(effects
				(font
					(size 1.27 1.27)
				)
				(justify mirror)
			)
		)
		(property "Value" ""
			(at 0 0 0)
			(layer "B.Fab")
			(effects
				(font
					(size 1.27 1.27)
				)
				(justify mirror)
			)
		)
		(duplicate_pad_numbers_are_jumpers no)
		(fp_poly
			(pts
				(xy 0.4953 -0.2032) (xy -0.4953 -0.2032) (xy -0.4953 1.6002) (xy 0.4953 1.6002)
			)
			(stroke
				(width 0)
				(type default)
			)
			(fill no)
			(layer "B.CrtYd")
		)
		(fp_line
			(start -0.4953 -0.2032)
			(end -0.4953 1.6002)
			(stroke
				(width 0.1)
				(type default)
			)
			(layer "B.Fab")
		)
		(fp_line
			(start -0.4953 1.6002)
			(end 0.4953 1.6002)
			(stroke
				(width 0.1)
				(type default)
			)
			(layer "B.Fab")
		)
		(fp_line
			(start 0.4953 -0.2032)
			(end -0.4953 -0.2032)
			(stroke
				(width 0.1)
				(type default)
			)
			(layer "B.Fab")
		)
		(fp_line
			(start 0.4953 1.6002)
			(end 0.4953 -0.2032)
			(stroke
				(width 0.1)
				(type default)
			)
			(layer "B.Fab")
		)
		(pad "1" smd rect
			(at 0 0 180)
			(size 0.762 0.889)
			(layers "B.Cu" "B.Mask" "B.Paste")
			(net "PVNN_PCH_STBY")
		)
		(pad "2" smd rect
			(at 0 1.397 180)
			(size 0.762 0.889)
			(layers "B.Cu" "B.Mask" "B.Paste")
			(net "GND")
		)
		(zone
			(layer "B.Cu")
			(hatch none 0.5)
			(connect_pads
				(clearance 0)
			)
			(min_thickness 0.25)
			(keepout
				(tracks not_allowed)
				(vias allowed)
				(pads allowed)
				(copperpour not_allowed)
				(footprints allowed)
			)
			(placement
				(enabled no)
				(sheetname "")
			)
			(fill
				(thermal_gap 0.5)
				(thermal_bridge_width 0.5)
				(island_removal_mode 0)
			)
			(polygon
				(pts
					(xy 374.396 -137.668) (xy 373.634 -137.668) (xy 373.634 -137.16) (xy 374.396 -137.16)
				)
			)
		)
	)
	(footprint ""
		(layer "B.Cu")
		(at 163.531042 -71.982076 180)
		(property "Reference" "R6P46"
			(at 0 0 0)
			(layer "B.SilkS")
			(hide yes)
			(effects
				(font
					(size 1.27 1.27)
				)
				(justify mirror)
			)
		)
		(property "Value" ""
			(at 0 0 0)
			(layer "B.Fab")
			(effects
				(font
					(size 1.27 1.27)
				)
				(justify mirror)
			)
		)
		(duplicate_pad_numbers_are_jumpers no)
		(fp_poly
			(pts
				(xy 0.2794 -0.1016) (xy -0.2794 -0.1016) (xy -0.2794 0.9906) (xy 0.2794 0.9906)
			)
			(stroke
				(width 0)
				(type default)
			)
			(fill no)
			(layer "B.CrtYd")
		)
		(fp_line
			(start 0.2794 0.9906)
			(end -0.2794 0.9906)
			(stroke
				(width 0.1)
				(type default)
			)
			(layer "B.Fab")
		)
		(fp_line
			(start 0.2794 -0.1016)
			(end 0.2794 0.9906)
			(stroke
				(width 0.1)
				(type default)
			)
			(layer "B.Fab")
		)
		(fp_line
			(start -0.2794 0.9906)
			(end -0.2794 -0.1016)
			(stroke
				(width 0.1)
				(type default)
			)
			(layer "B.Fab")
		)
		(fp_line
			(start -0.2794 -0.1016)
			(end 0.2794 -0.1016)
			(stroke
				(width 0.1)
				(type default)
			)
			(layer "B.Fab")
		)
		(pad "1" smd rect
			(at 0 0)
			(size 0.508 0.508)
			(layers "B.Cu" "B.Mask" "B.Paste")
			(net "PVCCIO_CPU0")
		)
		(pad "2" smd rect
			(at 0 0.889)
			(size 0.508 0.508)
			(layers "B.Cu" "B.Mask" "B.Paste")
			(net "XDP_CPU_MBP1_N")
		)
		(zone
			(layer "B.Cu")
			(hatch none 0.5)
			(connect_pads
				(clearance 0)
			)
			(min_thickness 0.25)
			(keepout
				(tracks not_allowed)
				(vias allowed)
				(pads allowed)
				(copperpour not_allowed)
				(footprints allowed)
			)
			(placement
				(enabled no)
				(sheetname "")
			)
			(fill
				(thermal_gap 0.5)
				(thermal_bridge_width 0.5)
				(island_removal_mode 0)
			)
			(polygon
				(pts
					(xy 163.277042 -72.617076) (xy 163.785042 -72.617076) (xy 163.785042 -72.236076) (xy 163.277042 -72.236076)
				)
			)
		)
		(zone
			(layer "B.Cu")
			(hatch none 0.5)
			(connect_pads
				(clearance 0)
			)
			(min_thickness 0.25)
			(keepout
				(tracks allowed)
				(vias not_allowed)
				(pads allowed)
				(copperpour not_allowed)
				(footprints allowed)
			)
			(placement
				(enabled no)
				(sheetname "")
			)
			(fill
				(thermal_gap 0.5)
				(thermal_bridge_width 0.5)
				(island_removal_mode 0)
			)
			(polygon
				(pts
					(xy 163.277042 -72.236076) (xy 163.785042 -72.236076) (xy 163.785042 -72.617076) (xy 163.277042 -72.617076)
				)
			)
		)
	)
	(footprint ""
		(layer "B.Cu")
		(at 107.8611 -3.3528 90)
		(property "Reference" "C5G91"
			(at -1.14681 0.76708 180)
			(unlocked yes)
			(layer "B.SilkS")
			(effects
				(font
					(size 0.7874 0.5842)
					(thickness 0.1524)
				)
				(justify mirror)
			)
		)
		(property "Value" ""
			(at 0 0 90)
			(layer "B.Fab")
			(effects
				(font
					(size 1.27 1.27)
				)
				(justify mirror)
			)
		)
		(duplicate_pad_numbers_are_jumpers no)
		(fp_rect
			(start -0.4953 -0.2032)
			(end 0.4953 1.6002)
			(stroke
				(width 0)
				(type default)
			)
			(fill no)
			(layer "B.CrtYd")
		)
		(fp_line
			(start 0.4953 -0.2032)
			(end -0.4953 -0.2032)
			(stroke
				(width 0.1)
				(type default)
			)
			(layer "B.Fab")
		)
		(fp_line
			(start -0.4953 -0.2032)
			(end -0.4953 1.6002)
			(stroke
				(width 0.1)
				(type default)
			)
			(layer "B.Fab")
		)
		(fp_line
			(start 0.4953 1.6002)
			(end 0.4953 -0.2032)
			(stroke
				(width 0.1)
				(type default)
			)
			(layer "B.Fab")
		)
		(fp_line
			(start -0.4953 1.6002)
			(end 0.4953 1.6002)
			(stroke
				(width 0.1)
				(type default)
			)
			(layer "B.Fab")
		)
		(pad "1" smd rect
			(at 0 0 270)
			(size 0.762 0.889)
			(layers "B.Cu" "B.Mask" "B.Paste")
			(net "PVDDQ_GHJ")
		)
		(pad "2" smd rect
			(at 0 1.397 270)
			(size 0.762 0.889)
			(layers "B.Cu" "B.Mask" "B.Paste")
			(net "GND")
		)
		(zone
			(layer "B.Cu")
			(hatch none 0.5)
			(connect_pads
				(clearance 0)
			)
			(min_thickness 0.25)
			(keepout
				(tracks not_allowed)
				(vias allowed)
				(pads allowed)
				(copperpour not_allowed)
				(footprints allowed)
			)
			(placement
				(enabled no)
				(sheetname "")
			)
			(fill
				(thermal_gap 0.5)
				(thermal_bridge_width 0.5)
				(island_removal_mode 0)
			)
			(polygon
				(pts
					(xy 108.3056 -2.9718) (xy 108.8136 -2.9718) (xy 108.8136 -3.7338) (xy 108.3056 -3.7338)
				)
			)
		)
	)
)
